FILE_TYPE = CONNECTIVITY;
{Allegro Design Entry HDL 17.2-2016 S081 (4005846) 1/11/2022}
"PAGE_NUMBER" = 7;
0"NC";
END.
